(kicad_pcb
	(version 20260206)
	(generator "pcbnew")
	(generator_version "10.0")
	(general
		(thickness 1.6)
		(legacy_teardrops no)
	)
	(paper "A4")
	(title_block
		(title "pdpb — Lightning_PDPB_BRD.brd")
		(comment 1 "Lightning (Wiwynn / Facebook NVMe JBOF) / footprints 725-731 of 1140")
	)
	(layers
		(0 "F.Cu" signal "TOP")
		(4 "In1.Cu" signal "L2GND")
		(6 "In2.Cu" signal "L3")
		(8 "In3.Cu" signal "L4VCC")
		(10 "In4.Cu" signal "L5VCC")
		(12 "In5.Cu" signal "L6")
		(14 "In6.Cu" signal "L7GND")
		(2 "B.Cu" signal "BOTTOM")
		(9 "F.Adhes" user "F.Adhesive")
		(11 "B.Adhes" user "B.Adhesive")
		(13 "F.Paste" user "Package Geometry/Pastemask Top")
		(15 "B.Paste" user "Package Geometry/Pastemask Bottom")
		(5 "F.SilkS" user "Ref Des/Silkscreen Top")
		(7 "B.SilkS" user "Ref Des/Silkscreen Bottom")
		(1 "F.Mask" user "Board Geometry/Soldermask Top")
		(3 "B.Mask" user "Board Geometry/Soldermask Bottom")
		(17 "Dwgs.User" user "User.Drawings")
		(19 "Cmts.User" user "User.Comments")
		(21 "Eco1.User" user "User.Eco1")
		(23 "Eco2.User" user "User.Eco2")
		(25 "Edge.Cuts" user "Board Geometry/Outline")
		(27 "Margin" user)
		(31 "F.CrtYd" user "Package Geometry/Place Bound Top")
		(29 "B.CrtYd" user "Package Geometry/Place Bound Bottom")
		(35 "F.Fab" user "Ref Des/Assembly Top")
		(33 "B.Fab" user "Ref Des/Assembly Bottom")
	)
	(footprint ""
		(layer "F.Cu")
		(at 207.391 -197.231 180)
		(property "Reference" "R9503"
			(at 0 0 180)
			(layer "F.SilkS")
			(hide yes)
			(effects
				(font
					(size 1.27 1.27)
				)
			)
		)
		(property "Value" "4K7R2J-2-GP"
			(at 0.064008 -3.993896 180)
			(unlocked yes)
			(layer "F.Fab")
			(hide yes)
			(effects
				(font
					(size 1.016 1.016)
					(thickness 0.1524)
				)
			)
		)
		(property "Device Type" "R402H16"
			(at 0.064008 -5.517896 180)
			(unlocked yes)
			(layer "F.Fab")
			(hide yes)
			(effects
				(font
					(size 1.016 1.016)
					(thickness 0.1524)
				)
			)
		)
		(duplicate_pad_numbers_are_jumpers no)
		(fp_line
			(start 0.508 -0.9398)
			(end -0.508 -0.9398)
			(stroke
				(width 0.1524)
				(type default)
			)
			(layer "F.SilkS")
		)
		(fp_line
			(start -0.508 -0.9398)
			(end -0.508 0.9398)
			(stroke
				(width 0.1524)
				(type default)
			)
			(layer "F.SilkS")
		)
		(fp_rect
			(start -0.508 0.9398)
			(end 0.508 -0.9398)
			(stroke
				(width 0)
				(type default)
			)
			(fill no)
			(layer "F.CrtYd")
		)
		(fp_rect
			(start -0.508 0.9398)
			(end 0.508 -0.9398)
			(stroke
				(width 0)
				(type default)
			)
			(fill no)
			(layer "F.Fab")
		)
		(pad "1" smd custom
			(at 0 -0.4445 180)
			(size 0.1397 0.1397)
			(layers "F.Cu" "F.Mask" "F.Paste")
			(net "P3V3")
			(options
				(clearance outline)
				(anchor circle)
			)
			(primitives
				(gr_poly
					(pts
						(arc
							(start -0.1778 -0.2794)
							(mid -0.249642 -0.249642)
							(end -0.2794 -0.1778)
						)
						(arc
							(start -0.2794 0.1778)
							(mid -0.249642 0.249642)
							(end -0.1778 0.2794)
						)
						(arc
							(start 0.1778 0.2794)
							(mid 0.249642 0.249642)
							(end 0.2794 0.1778)
						)
						(arc
							(start 0.2794 -0.1778)
							(mid 0.249642 -0.249642)
							(end 0.1778 -0.2794)
						)
					)
					(width 0)
					(fill yes)
				)
			)
		)
		(pad "2" smd custom
			(at 0 0.4445 180)
			(size 0.1397 0.1397)
			(layers "F.Cu" "F.Mask" "F.Paste")
			(net "SSD3_PWREN")
			(options
				(clearance outline)
				(anchor circle)
			)
			(primitives
				(gr_poly
					(pts
						(arc
							(start -0.1778 -0.2794)
							(mid -0.249642 -0.249642)
							(end -0.2794 -0.1778)
						)
						(arc
							(start -0.2794 0.1778)
							(mid -0.249642 0.249642)
							(end -0.1778 0.2794)
						)
						(arc
							(start 0.1778 0.2794)
							(mid 0.249642 0.249642)
							(end 0.2794 0.1778)
						)
						(arc
							(start 0.2794 -0.1778)
							(mid 0.249642 -0.249642)
							(end 0.1778 -0.2794)
						)
					)
					(width 0)
					(fill yes)
				)
			)
		)
	)
	(footprint ""
		(layer "F.Cu")
		(at 88.011 -86.614 -90)
		(property "Reference" "R9395"
			(at 0 0 270)
			(layer "F.SilkS")
			(hide yes)
			(effects
				(font
					(size 1.27 1.27)
				)
			)
		)
		(property "Value" "4K7R2J-2-GP"
			(at 0.064008 -3.993896 270)
			(unlocked yes)
			(layer "F.Fab")
			(hide yes)
			(effects
				(font
					(size 1.016 1.016)
					(thickness 0.1524)
				)
			)
		)
		(property "Device Type" "R402H16"
			(at 0.064008 -5.517896 270)
			(unlocked yes)
			(layer "F.Fab")
			(hide yes)
			(effects
				(font
					(size 1.016 1.016)
					(thickness 0.1524)
				)
			)
		)
		(duplicate_pad_numbers_are_jumpers no)
		(fp_line
			(start -0.508 -0.9398)
			(end -0.508 0.9398)
			(stroke
				(width 0.1524)
				(type default)
			)
			(layer "F.SilkS")
		)
		(fp_line
			(start 0.508 -0.9398)
			(end -0.508 -0.9398)
			(stroke
				(width 0.1524)
				(type default)
			)
			(layer "F.SilkS")
		)
		(fp_rect
			(start -0.508 0.9398)
			(end 0.508 -0.9398)
			(stroke
				(width 0)
				(type default)
			)
			(fill no)
			(layer "F.CrtYd")
		)
		(fp_rect
			(start -0.508 0.9398)
			(end 0.508 -0.9398)
			(stroke
				(width 0)
				(type default)
			)
			(fill no)
			(layer "F.Fab")
		)
		(pad "1" smd custom
			(at 0 -0.4445 270)
			(size 0.1397 0.1397)
			(layers "F.Cu" "F.Mask" "F.Paste")
			(net "P3V3")
			(options
				(clearance outline)
				(anchor circle)
			)
			(primitives
				(gr_poly
					(pts
						(arc
							(start -0.1778 -0.2794)
							(mid -0.249642 -0.249642)
							(end -0.2794 -0.1778)
						)
						(arc
							(start -0.2794 0.1778)
							(mid -0.249642 0.249642)
							(end -0.1778 0.2794)
						)
						(arc
							(start 0.1778 0.2794)
							(mid 0.249642 0.249642)
							(end 0.2794 0.1778)
						)
						(arc
							(start 0.2794 -0.1778)
							(mid 0.249642 -0.249642)
							(end 0.1778 -0.2794)
						)
					)
					(width 0)
					(fill yes)
				)
			)
		)
		(pad "2" smd custom
			(at 0 0.4445 270)
			(size 0.1397 0.1397)
			(layers "F.Cu" "F.Mask" "F.Paste")
			(net "SSD_PRSNT_NET9")
			(options
				(clearance outline)
				(anchor circle)
			)
			(primitives
				(gr_poly
					(pts
						(arc
							(start -0.1778 -0.2794)
							(mid -0.249642 -0.249642)
							(end -0.2794 -0.1778)
						)
						(arc
							(start -0.2794 0.1778)
							(mid -0.249642 0.249642)
							(end -0.1778 0.2794)
						)
						(arc
							(start 0.1778 0.2794)
							(mid 0.249642 0.249642)
							(end 0.2794 0.1778)
						)
						(arc
							(start 0.2794 -0.1778)
							(mid 0.249642 -0.249642)
							(end 0.1778 -0.2794)
						)
					)
					(width 0)
					(fill yes)
				)
			)
		)
	)
	(footprint ""
		(layer "F.Cu")
		(at 94.869 -26.162)
		(property "Reference" "C358"
			(at 0 0 0)
			(layer "F.SilkS")
			(hide yes)
			(effects
				(font
					(size 1.27 1.27)
				)
			)
		)
		(property "Value" "SCD1U16V2KX-3GP"
			(at 1.1811 -2.7051 0)
			(unlocked yes)
			(layer "F.Fab")
			(hide yes)
			(effects
				(font
					(size 1.016 1.016)
					(thickness 0.1524)
				)
			)
		)
		(property "Device Type" "C402H22"
			(at 1.1811 -4.2291 0)
			(unlocked yes)
			(layer "F.Fab")
			(hide yes)
			(effects
				(font
					(size 1.016 1.016)
					(thickness 0.1524)
				)
			)
		)
		(duplicate_pad_numbers_are_jumpers no)
		(fp_rect
			(start -0.4318 0.9525)
			(end 0.4318 -0.9525)
			(stroke
				(width 0)
				(type default)
			)
			(fill no)
			(layer "F.CrtYd")
		)
		(fp_rect
			(start -0.4318 0.9525)
			(end 0.4318 -0.9525)
			(stroke
				(width 0)
				(type default)
			)
			(fill no)
			(layer "F.Fab")
		)
		(pad "1" smd custom
			(at 0 -0.4445)
			(size 0.1524 0.1524)
			(layers "F.Cu" "F.Mask" "F.Paste")
			(net "P3V3_SENSE")
			(options
				(clearance outline)
				(anchor circle)
			)
			(primitives
				(gr_poly
					(pts
						(arc
							(start 0.3048 -0.2032)
							(mid 0.275042 -0.275042)
							(end 0.2032 -0.3048)
						)
						(arc
							(start -0.2032 -0.3048)
							(mid -0.275042 -0.275042)
							(end -0.3048 -0.2032)
						)
						(arc
							(start -0.3048 0.2032)
							(mid -0.275042 0.275042)
							(end -0.2032 0.3048)
						)
						(arc
							(start 0.2032 0.3048)
							(mid 0.275042 0.275042)
							(end 0.3048 0.2032)
						)
					)
					(width 0)
					(fill yes)
				)
			)
		)
		(pad "2" smd custom
			(at 0 0.4445)
			(size 0.1524 0.1524)
			(layers "F.Cu" "F.Mask" "F.Paste")
			(net "GND")
			(options
				(clearance outline)
				(anchor circle)
			)
			(primitives
				(gr_poly
					(pts
						(arc
							(start 0.3048 -0.2032)
							(mid 0.275042 -0.275042)
							(end 0.2032 -0.3048)
						)
						(arc
							(start -0.2032 -0.3048)
							(mid -0.275042 -0.275042)
							(end -0.3048 -0.2032)
						)
						(arc
							(start -0.3048 0.2032)
							(mid -0.275042 0.275042)
							(end -0.2032 0.3048)
						)
						(arc
							(start 0.2032 0.3048)
							(mid 0.275042 0.275042)
							(end 0.3048 0.2032)
						)
					)
					(width 0)
					(fill yes)
				)
			)
		)
	)
	(footprint ""
		(layer "F.Cu")
		(at 78.3844 -211.2772)
		(property "Reference" "R9968"
			(at 0 0 0)
			(layer "F.SilkS")
			(hide yes)
			(effects
				(font
					(size 1.27 1.27)
				)
			)
		)
		(property "Value" "470R2F-GP"
			(at 0.064008 -3.993896 0)
			(unlocked yes)
			(layer "F.Fab")
			(hide yes)
			(effects
				(font
					(size 1.016 1.016)
					(thickness 0.1524)
				)
			)
		)
		(property "Device Type" "R402H16"
			(at 0.064008 -5.517896 0)
			(unlocked yes)
			(layer "F.Fab")
			(hide yes)
			(effects
				(font
					(size 1.016 1.016)
					(thickness 0.1524)
				)
			)
		)
		(duplicate_pad_numbers_are_jumpers no)
		(fp_line
			(start -0.508 -0.9398)
			(end -0.508 0.9398)
			(stroke
				(width 0.1524)
				(type default)
			)
			(layer "F.SilkS")
		)
		(fp_line
			(start 0.508 -0.9398)
			(end -0.508 -0.9398)
			(stroke
				(width 0.1524)
				(type default)
			)
			(layer "F.SilkS")
		)
		(fp_rect
			(start -0.508 0.9398)
			(end 0.508 -0.9398)
			(stroke
				(width 0)
				(type default)
			)
			(fill no)
			(layer "F.CrtYd")
		)
		(fp_rect
			(start -0.508 0.9398)
			(end 0.508 -0.9398)
			(stroke
				(width 0)
				(type default)
			)
			(fill no)
			(layer "F.Fab")
		)
		(pad "1" smd custom
			(at 0 -0.4445)
			(size 0.1397 0.1397)
			(layers "F.Cu" "F.Mask" "F.Paste")
			(net "VDD_DIFF_3")
			(options
				(clearance outline)
				(anchor circle)
			)
			(primitives
				(gr_poly
					(pts
						(arc
							(start -0.1778 -0.2794)
							(mid -0.249642 -0.249642)
							(end -0.2794 -0.1778)
						)
						(arc
							(start -0.2794 0.1778)
							(mid -0.249642 0.249642)
							(end -0.1778 0.2794)
						)
						(arc
							(start 0.1778 0.2794)
							(mid 0.249642 0.249642)
							(end 0.2794 0.1778)
						)
						(arc
							(start 0.2794 -0.1778)
							(mid 0.249642 -0.249642)
							(end 0.1778 -0.2794)
						)
					)
					(width 0)
					(fill yes)
				)
			)
		)
		(pad "2" smd custom
			(at 0 0.4445)
			(size 0.1397 0.1397)
			(layers "F.Cu" "F.Mask" "F.Paste")
			(net "PE_100M_CLK2_P")
			(options
				(clearance outline)
				(anchor circle)
			)
			(primitives
				(gr_poly
					(pts
						(arc
							(start -0.1778 -0.2794)
							(mid -0.249642 -0.249642)
							(end -0.2794 -0.1778)
						)
						(arc
							(start -0.2794 0.1778)
							(mid -0.249642 0.249642)
							(end -0.1778 0.2794)
						)
						(arc
							(start 0.1778 0.2794)
							(mid 0.249642 0.249642)
							(end 0.2794 0.1778)
						)
						(arc
							(start 0.2794 -0.1778)
							(mid 0.249642 -0.249642)
							(end 0.1778 -0.2794)
						)
					)
					(width 0)
					(fill yes)
				)
			)
		)
	)
	(footprint ""
		(layer "F.Cu")
		(at 29.0322 -17.145 180)
		(property "Reference" "R417"
			(at 0 0 180)
			(layer "F.SilkS")
			(hide yes)
			(effects
				(font
					(size 1.27 1.27)
				)
			)
		)
		(property "Value" "0R2J-2-GP"
			(at 0.064008 -3.993896 180)
			(unlocked yes)
			(layer "F.Fab")
			(hide yes)
			(effects
				(font
					(size 1.016 1.016)
					(thickness 0.1524)
				)
			)
		)
		(property "Device Type" "R402H16"
			(at 0.064008 -5.517896 180)
			(unlocked yes)
			(layer "F.Fab")
			(hide yes)
			(effects
				(font
					(size 1.016 1.016)
					(thickness 0.1524)
				)
			)
		)
		(duplicate_pad_numbers_are_jumpers no)
		(fp_line
			(start 0.508 -0.9398)
			(end -0.508 -0.9398)
			(stroke
				(width 0.1524)
				(type default)
			)
			(layer "F.SilkS")
		)
		(fp_line
			(start -0.508 -0.9398)
			(end -0.508 0.9398)
			(stroke
				(width 0.1524)
				(type default)
			)
			(layer "F.SilkS")
		)
		(fp_rect
			(start -0.508 0.9398)
			(end 0.508 -0.9398)
			(stroke
				(width 0)
				(type default)
			)
			(fill no)
			(layer "F.CrtYd")
		)
		(fp_rect
			(start -0.508 0.9398)
			(end 0.508 -0.9398)
			(stroke
				(width 0)
				(type default)
			)
			(fill no)
			(layer "F.Fab")
		)
		(pad "1" smd custom
			(at 0 -0.4445 180)
			(size 0.1397 0.1397)
			(layers "F.Cu" "F.Mask" "F.Paste")
			(net "SCL_DR14_R")
			(options
				(clearance outline)
				(anchor circle)
			)
			(primitives
				(gr_poly
					(pts
						(arc
							(start -0.1778 -0.2794)
							(mid -0.249642 -0.249642)
							(end -0.2794 -0.1778)
						)
						(arc
							(start -0.2794 0.1778)
							(mid -0.249642 0.249642)
							(end -0.1778 0.2794)
						)
						(arc
							(start 0.1778 0.2794)
							(mid 0.249642 0.249642)
							(end 0.2794 0.1778)
						)
						(arc
							(start 0.2794 -0.1778)
							(mid 0.249642 -0.249642)
							(end 0.1778 -0.2794)
						)
					)
					(width 0)
					(fill yes)
				)
			)
		)
		(pad "2" smd custom
			(at 0 0.4445 180)
			(size 0.1397 0.1397)
			(layers "F.Cu" "F.Mask" "F.Paste")
			(net "SCL_DR14")
			(options
				(clearance outline)
				(anchor circle)
			)
			(primitives
				(gr_poly
					(pts
						(arc
							(start -0.1778 -0.2794)
							(mid -0.249642 -0.249642)
							(end -0.2794 -0.1778)
						)
						(arc
							(start -0.2794 0.1778)
							(mid -0.249642 0.249642)
							(end -0.1778 0.2794)
						)
						(arc
							(start 0.1778 0.2794)
							(mid 0.249642 0.249642)
							(end 0.2794 0.1778)
						)
						(arc
							(start 0.2794 -0.1778)
							(mid 0.249642 -0.249642)
							(end 0.1778 -0.2794)
						)
					)
					(width 0)
					(fill yes)
				)
			)
		)
	)
	(footprint ""
		(layer "F.Cu")
		(at 32.11703 -84.662518 180)
		(property "Reference" "SR1110"
			(at 0 0 180)
			(layer "F.SilkS")
			(hide yes)
			(effects
				(font
					(size 1.27 1.27)
				)
			)
		)
		(property "Value" "4K7R2F-GP"
			(at 0.064008 -3.993896 180)
			(unlocked yes)
			(layer "F.Fab")
			(hide yes)
			(effects
				(font
					(size 1.016 1.016)
					(thickness 0.1524)
				)
			)
		)
		(property "Device Type" "R402H16"
			(at 0.064008 -5.517896 180)
			(unlocked yes)
			(layer "F.Fab")
			(hide yes)
			(effects
				(font
					(size 1.016 1.016)
					(thickness 0.1524)
				)
			)
		)
		(duplicate_pad_numbers_are_jumpers no)
		(fp_line
			(start 0.508 -0.9398)
			(end -0.508 -0.9398)
			(stroke
				(width 0.1524)
				(type default)
			)
			(layer "F.SilkS")
		)
		(fp_line
			(start -0.508 -0.9398)
			(end -0.508 0.9398)
			(stroke
				(width 0.1524)
				(type default)
			)
			(layer "F.SilkS")
		)
		(fp_rect
			(start -0.508 0.9398)
			(end 0.508 -0.9398)
			(stroke
				(width 0)
				(type default)
			)
			(fill no)
			(layer "F.CrtYd")
		)
		(fp_rect
			(start -0.508 0.9398)
			(end 0.508 -0.9398)
			(stroke
				(width 0)
				(type default)
			)
			(fill no)
			(layer "F.Fab")
		)
		(pad "1" smd custom
			(at 0 -0.4445 180)
			(size 0.1397 0.1397)
			(layers "F.Cu" "F.Mask" "F.Paste")
			(net "DUALPORTEN#9")
			(options
				(clearance outline)
				(anchor circle)
			)
			(primitives
				(gr_poly
					(pts
						(arc
							(start -0.1778 -0.2794)
							(mid -0.249642 -0.249642)
							(end -0.2794 -0.1778)
						)
						(arc
							(start -0.2794 0.1778)
							(mid -0.249642 0.249642)
							(end -0.1778 0.2794)
						)
						(arc
							(start 0.1778 0.2794)
							(mid 0.249642 0.249642)
							(end 0.2794 0.1778)
						)
						(arc
							(start 0.2794 -0.1778)
							(mid 0.249642 -0.249642)
							(end 0.1778 -0.2794)
						)
					)
					(width 0)
					(fill yes)
				)
			)
		)
		(pad "2" smd custom
			(at 0 0.4445 180)
			(size 0.1397 0.1397)
			(layers "F.Cu" "F.Mask" "F.Paste")
			(net "GND")
			(options
				(clearance outline)
				(anchor circle)
			)
			(primitives
				(gr_poly
					(pts
						(arc
							(start -0.1778 -0.2794)
							(mid -0.249642 -0.249642)
							(end -0.2794 -0.1778)
						)
						(arc
							(start -0.2794 0.1778)
							(mid -0.249642 0.249642)
							(end -0.1778 0.2794)
						)
						(arc
							(start 0.1778 0.2794)
							(mid 0.249642 0.249642)
							(end 0.2794 0.1778)
						)
						(arc
							(start 0.2794 -0.1778)
							(mid 0.249642 -0.249642)
							(end 0.1778 -0.2794)
						)
					)
					(width 0)
					(fill yes)
				)
			)
		)
	)
	(footprint ""
		(layer "F.Cu")
		(at 82.931 -217.17 90)
		(property "Reference" "R9356"
			(at 0 0 90)
			(layer "F.SilkS")
			(hide yes)
			(effects
				(font
					(size 1.27 1.27)
				)
			)
		)
		(property "Value" "2D2R2F-GP"
			(at 0.064008 -3.993896 90)
			(unlocked yes)
			(layer "F.Fab")
			(hide yes)
			(effects
				(font
					(size 1.016 1.016)
					(thickness 0.1524)
				)
			)
		)
		(property "Device Type" "R402H16"
			(at 0.064008 -5.517896 90)
			(unlocked yes)
			(layer "F.Fab")
			(hide yes)
			(effects
				(font
					(size 1.016 1.016)
					(thickness 0.1524)
				)
			)
		)
		(duplicate_pad_numbers_are_jumpers no)
		(fp_line
			(start 0.508 -0.9398)
			(end -0.508 -0.9398)
			(stroke
				(width 0.1524)
				(type default)
			)
			(layer "F.SilkS")
		)
		(fp_line
			(start -0.508 -0.9398)
			(end -0.508 0.9398)
			(stroke
				(width 0.1524)
				(type default)
			)
			(layer "F.SilkS")
		)
		(fp_rect
			(start -0.508 0.9398)
			(end 0.508 -0.9398)
			(stroke
				(width 0)
				(type default)
			)
			(fill no)
			(layer "F.CrtYd")
		)
		(fp_rect
			(start -0.508 0.9398)
			(end 0.508 -0.9398)
			(stroke
				(width 0)
				(type default)
			)
			(fill no)
			(layer "F.Fab")
		)
		(pad "1" smd custom
			(at 0 -0.4445 90)
			(size 0.1397 0.1397)
			(layers "F.Cu" "F.Mask" "F.Paste")
			(net "VDD_DIFF_3")
			(options
				(clearance outline)
				(anchor circle)
			)
			(primitives
				(gr_poly
					(pts
						(arc
							(start -0.1778 -0.2794)
							(mid -0.249642 -0.249642)
							(end -0.2794 -0.1778)
						)
						(arc
							(start -0.2794 0.1778)
							(mid -0.249642 0.249642)
							(end -0.1778 0.2794)
						)
						(arc
							(start 0.1778 0.2794)
							(mid 0.249642 0.249642)
							(end 0.2794 0.1778)
						)
						(arc
							(start 0.2794 -0.1778)
							(mid 0.249642 -0.249642)
							(end 0.1778 -0.2794)
						)
					)
					(width 0)
					(fill yes)
				)
			)
		)
		(pad "2" smd custom
			(at 0 0.4445 90)
			(size 0.1397 0.1397)
			(layers "F.Cu" "F.Mask" "F.Paste")
			(net "VDDA_3")
			(options
				(clearance outline)
				(anchor circle)
			)
			(primitives
				(gr_poly
					(pts
						(arc
							(start -0.1778 -0.2794)
							(mid -0.249642 -0.249642)
							(end -0.2794 -0.1778)
						)
						(arc
							(start -0.2794 0.1778)
							(mid -0.249642 0.249642)
							(end -0.1778 0.2794)
						)
						(arc
							(start 0.1778 0.2794)
							(mid 0.249642 0.249642)
							(end 0.2794 0.1778)
						)
						(arc
							(start 0.2794 -0.1778)
							(mid 0.249642 -0.249642)
							(end 0.1778 -0.2794)
						)
					)
					(width 0)
					(fill yes)
				)
			)
		)
	)
)
